(kicad_pcb
	(version 20260206)
	(generator "pcbnew")
	(generator_version "10.0")
	(general
		(thickness 1.6)
		(legacy_teardrops no)
	)
	(paper "A4")
	(title_block
		(title "15969-1a.1015WZS0858.brd")
		(comment 1 "Tioga Pass / footprint 150 of 295 (SLOT3), pads 152-166 of 166")
	)
	(layers
		(0 "F.Cu" signal "TOP")
		(4 "In1.Cu" signal "L2GND")
		(6 "In2.Cu" signal "L3")
		(8 "In3.Cu" signal "L4")
		(10 "In4.Cu" signal "L5GND")
		(2 "B.Cu" signal "BOTTOM")
		(9 "F.Adhes" user "F.Adhesive")
		(11 "B.Adhes" user "B.Adhesive")
		(13 "F.Paste" user "Package Geometry/Pastemask Top")
		(15 "B.Paste" user "Package Geometry/Pastemask Bottom")
		(5 "F.SilkS" user "Ref Des/Silkscreen Top")
		(7 "B.SilkS" user "Ref Des/Silkscreen Bottom")
		(1 "F.Mask" user "Board Geometry/Soldermask Top")
		(3 "B.Mask" user "Board Geometry/Soldermask Bottom")
		(17 "Dwgs.User" user "User.Drawings")
		(19 "Cmts.User" user "User.Comments")
		(21 "Eco1.User" user "User.Eco1")
		(23 "Eco2.User" user "User.Eco2")
		(25 "Edge.Cuts" user "Board Geometry/Outline")
		(27 "Margin" user)
		(31 "F.CrtYd" user "Package Geometry/Place Bound Top")
		(29 "B.CrtYd" user "Package Geometry/Place Bound Bottom")
		(35 "F.Fab" user "Ref Des/Assembly Top")
		(33 "B.Fab" user "Ref Des/Assembly Bottom")
	)
	(footprint ""
		(layer "F.Cu")
		(at 42.729912 -30.820106)
		(property "Reference" "SLOT3"
			(at 0 0 0)
			(layer "F.SilkS")
			(hide yes)
			(effects
				(font
					(size 1.27 1.27)
				)
			)
		)
		(property "Value" "PCISLT164-129-GP"
			(at -15.9639 4.8514 0)
			(unlocked yes)
			(layer "F.Fab")
			(hide yes)
			(effects
				(font
					(size 1.016 1.016)
					(thickness 0.1524)
				)
			)
		)
		(property "Device Type" "10018783-10203TLF"
			(at -15.9639 3.3274 0)
			(unlocked yes)
			(layer "F.Fab")
			(hide yes)
			(effects
				(font
					(size 1.016 1.016)
					(thickness 0.1524)
				)
			)
		)
		(duplicate_pad_numbers_are_jumpers no)
		(pad "B68" thru_hole circle
			(at 57.34939 3.24993)
			(size 1.0668 1.0668)
			(drill 0.7112)
			(layers "*.Cu" "*.Mask")
			(remove_unused_layers no)
			(net "GND")
			(clearance 0.1778)
			(thermal_gap 0.1778)
		)
		(pad "B69" thru_hole circle
			(at 58.35015 1.24968)
			(size 1.0668 1.0668)
			(drill 0.7112)
			(layers "*.Cu" "*.Mask")
			(remove_unused_layers no)
			(net "GND")
			(clearance 0.1778)
			(thermal_gap 0.1778)
		)
		(pad "B70" thru_hole circle
			(at 59.34964 3.24993)
			(size 1.0668 1.0668)
			(drill 0.7112)
			(layers "*.Cu" "*.Mask")
			(remove_unused_layers no)
			(net "P3E_CPU0_PE2_SS_C_TXP<13>")
			(clearance 0.1778)
			(thermal_gap 0.1778)
		)
		(pad "B71" thru_hole circle
			(at 60.3504 1.24968)
			(size 1.0668 1.0668)
			(drill 0.7112)
			(layers "*.Cu" "*.Mask")
			(remove_unused_layers no)
			(net "P3E_CPU0_PE2_SS_C_TXN<13>")
			(clearance 0.1778)
			(thermal_gap 0.1778)
		)
		(pad "B72" thru_hole circle
			(at 61.34989 3.24993)
			(size 1.0668 1.0668)
			(drill 0.7112)
			(layers "*.Cu" "*.Mask")
			(remove_unused_layers no)
			(net "GND")
			(clearance 0.1778)
			(thermal_gap 0.1778)
		)
		(pad "B73" thru_hole circle
			(at 62.34938 1.24968)
			(size 1.0668 1.0668)
			(drill 0.7112)
			(layers "*.Cu" "*.Mask")
			(remove_unused_layers no)
			(net "GND")
			(clearance 0.1778)
			(thermal_gap 0.1778)
		)
		(pad "B74" thru_hole circle
			(at 63.35014 3.24993)
			(size 1.0668 1.0668)
			(drill 0.7112)
			(layers "*.Cu" "*.Mask")
			(remove_unused_layers no)
			(net "P3E_CPU0_PE2_SS_C_TXP<14>")
			(clearance 0.1778)
			(thermal_gap 0.1778)
		)
		(pad "B75" thru_hole circle
			(at 64.34963 1.24968)
			(size 1.0668 1.0668)
			(drill 0.7112)
			(layers "*.Cu" "*.Mask")
			(remove_unused_layers no)
			(net "P3E_CPU0_PE2_SS_C_TXN<14>")
			(clearance 0.1778)
			(thermal_gap 0.1778)
		)
		(pad "B76" thru_hole circle
			(at 65.35039 3.24993)
			(size 1.0668 1.0668)
			(drill 0.7112)
			(layers "*.Cu" "*.Mask")
			(remove_unused_layers no)
			(net "GND")
			(clearance 0.1778)
			(thermal_gap 0.1778)
		)
		(pad "B77" thru_hole circle
			(at 66.34988 1.24968)
			(size 1.0668 1.0668)
			(drill 0.7112)
			(layers "*.Cu" "*.Mask")
			(remove_unused_layers no)
			(net "GND")
			(clearance 0.1778)
			(thermal_gap 0.1778)
		)
		(pad "B78" thru_hole circle
			(at 67.34937 3.24993)
			(size 1.0668 1.0668)
			(drill 0.7112)
			(layers "*.Cu" "*.Mask")
			(remove_unused_layers no)
			(net "P3E_CPU0_PE2_SS_C_TXP<15>")
			(clearance 0.1778)
			(thermal_gap 0.1778)
		)
		(pad "B79" thru_hole circle
			(at 68.35013 1.24968)
			(size 1.0668 1.0668)
			(drill 0.7112)
			(layers "*.Cu" "*.Mask")
			(remove_unused_layers no)
			(net "P3E_CPU0_PE2_SS_C_TXN<15>")
			(clearance 0.1778)
			(thermal_gap 0.1778)
		)
		(pad "B80" thru_hole circle
			(at 69.34962 3.24993)
			(size 1.0668 1.0668)
			(drill 0.7112)
			(layers "*.Cu" "*.Mask")
			(remove_unused_layers no)
			(net "GND")
			(clearance 0.1778)
			(thermal_gap 0.1778)
		)
		(pad "B81" thru_hole circle
			(at 70.35038 1.24968)
			(size 1.0668 1.0668)
			(drill 0.7112)
			(layers "*.Cu" "*.Mask")
			(remove_unused_layers no)
			(net "PCIE_SLOT3_PRSNT2_4_N")
			(clearance 0.1778)
			(thermal_gap 0.1778)
		)
		(pad "B82" thru_hole circle
			(at 71.34987 3.24993)
			(size 1.0668 1.0668)
			(drill 0.7112)
			(layers "*.Cu" "*.Mask")
			(remove_unused_layers no)
			(net "TP_RSVD_SLOT3_PIN82")
			(clearance 0.1778)
			(thermal_gap 0.1778)
		)
	)
)
